(kicad_pcb
	(version 20241229)
	(generator "pcbnew")
	(generator_version "9.0")
	(general
		(thickness 1.6642)
		(legacy_teardrops no)
	)
	(paper "A3")
	(title_block
		(title "PolarFire SoM")
		(date "2025-07-22")
		(rev "1.1.4")
		(company "Antmicro Ltd")
		(comment 1 "www.antmicro.com")
		(comment 9 "footprints 469-470 of 470")
	)
	(layers
		(0 "F.Cu" mixed)
		(4 "In1.Cu" power)
		(6 "In2.Cu" signal)
		(8 "In3.Cu" power)
		(10 "In4.Cu" signal)
		(12 "In5.Cu" power)
		(14 "In6.Cu" power)
		(16 "In7.Cu" signal)
		(18 "In8.Cu" power)
		(20 "In9.Cu" signal)
		(22 "In10.Cu" power)
		(24 "In11.Cu" signal)
		(26 "In12.Cu" signal)
		(2 "B.Cu" mixed)
		(9 "F.Adhes" user "F.Adhesive")
		(11 "B.Adhes" user "B.Adhesive")
		(13 "F.Paste" user)
		(15 "B.Paste" user)
		(5 "F.SilkS" user "F.Silkscreen")
		(7 "B.SilkS" user "B.Silkscreen")
		(1 "F.Mask" user)
		(3 "B.Mask" user)
		(17 "Dwgs.User" user "User.Drawings")
		(19 "Cmts.User" user "User.Comments")
		(21 "Eco1.User" user "User.Eco1")
		(23 "Eco2.User" user "User.Eco2")
		(25 "Edge.Cuts" user)
		(27 "Margin" user)
		(31 "F.CrtYd" user "F.Courtyard")
		(29 "B.CrtYd" user "B.Courtyard")
		(35 "F.Fab" user)
		(33 "B.Fab" user)
	)
	(footprint "antmicro-footprints:XSON-8_1x1.95mm_P0.5mm"
		(layer "B.Cu")
		(at 219.32 141.62)
		(property "Reference" "U29"
			(at -1.78 2.15 0)
			(layer "B.SilkS")
			(effects
				(font
					(size 0.7 0.7)
					(thickness 0.15)
				)
				(justify right bottom mirror)
			)
		)
		(property "Value" "NTS0102_XSON"
			(at 0 -2.2 0)
			(layer "B.Fab")
			(hide yes)
			(effects
				(font
					(size 0.7 0.7)
					(thickness 0.15)
				)
				(justify right bottom mirror)
			)
		)
		(property "Datasheet" "http://www.farnell.com/datasheets/1760723.pdf"
			(at 0 0 0)
			(layer "F.Fab")
			(hide yes)
			(effects
				(font
					(size 1.27 1.27)
					(thickness 0.15)
				)
			)
		)
		(property "Description" "Transceiver, 1.65 V to 3.6 V, XSON-8"
			(at 0 0 0)
			(layer "F.Fab")
			(hide yes)
			(effects
				(font
					(size 1.27 1.27)
					(thickness 0.15)
				)
			)
		)
		(property "Author" "Antmicro"
			(at 0 0 0)
			(layer "B.Fab")
			(hide yes)
			(effects
				(font
					(size 1 1)
					(thickness 0.15)
				)
				(justify mirror)
			)
		)
		(property "License" "Apache-2.0"
			(at 0 0 0)
			(layer "B.Fab")
			(hide yes)
			(effects
				(font
					(size 1 1)
					(thickness 0.15)
				)
				(justify mirror)
			)
		)
		(property "MPN" "NTS0102GT"
			(at 0 0 0)
			(layer "B.Fab")
			(hide yes)
			(effects
				(font
					(size 1 1)
					(thickness 0.15)
				)
				(justify mirror)
			)
		)
		(property "Manufacturer" "NXP"
			(at 0 0 0)
			(layer "B.Fab")
			(hide yes)
			(effects
				(font
					(size 1 1)
					(thickness 0.15)
				)
				(justify mirror)
			)
		)
		(sheetname "/FPGA GPIO/")
		(sheetfile "fpga-gpio.kicad_sch")
		(attr smd)
		(fp_line
			(start -0.5 1.1)
			(end 0.5 1.1)
			(stroke
				(width 0.15)
				(type solid)
			)
			(layer "B.SilkS")
		)
		(fp_line
			(start 0.5 -1.1)
			(end -0.5 -1.1)
			(stroke
				(width 0.15)
				(type solid)
			)
			(layer "B.SilkS")
		)
		(fp_circle
			(center -0.75 1.1)
			(end -0.701 1.1)
			(stroke
				(width 0.15)
				(type solid)
			)
			(fill no)
			(layer "B.SilkS")
		)
		(fp_rect
			(start -0.8 1.2)
			(end 0.8 -1.2)
			(stroke
				(width 0.05)
				(type solid)
			)
			(fill no)
			(layer "B.CrtYd")
		)
		(fp_line
			(start -0.5305 -1)
			(end -0.5305 1.001)
			(stroke
				(width 0.15)
				(type solid)
			)
			(layer "B.Fab")
		)
		(fp_line
			(start -0.5305 1.001)
			(end 0.5305 1.001)
			(stroke
				(width 0.15)
				(type solid)
			)
			(layer "B.Fab")
		)
		(fp_line
			(start 0.5305 -1)
			(end -0.5305 -1)
			(stroke
				(width 0.15)
				(type solid)
			)
			(layer "B.Fab")
		)
		(fp_line
			(start 0.5305 1.001)
			(end 0.5305 -1)
			(stroke
				(width 0.15)
				(type solid)
			)
			(layer "B.Fab")
		)
		(fp_text user "${REFERENCE}"
			(at -0.527 -5.905 180)
			(layer "B.Fab")
			(effects
				(font
					(size 0.7 0.7)
					(thickness 0.15)
				)
				(justify left bottom mirror)
			)
		)
		(fp_text user "License: Apache-2.0"
			(at -0.527 -8.306 180)
			(layer "B.Fab")
			(effects
				(font
					(size 0.7 0.7)
					(thickness 0.15)
				)
				(justify left bottom mirror)
			)
		)
		(fp_text user "Author: Antmicro"
			(at -0.527 -7.105 180)
			(layer "B.Fab")
			(effects
				(font
					(size 0.7 0.7)
					(thickness 0.15)
				)
				(justify left bottom mirror)
			)
		)
		(pad "1" smd roundrect
			(at -0.45 0.75 180)
			(size 0.6 0.3)
			(layers "B.Cu" "B.Mask" "B.Paste")
			(roundrect_rratio 0.25)
			(net 129 "/FPGA GPIO/WiFi.CLK")
			(pinfunction "B_{2}")
			(pintype "bidirectional")
		)
		(pad "2" smd roundrect
			(at -0.45 0.25 180)
			(size 0.6 0.25)
			(layers "B.Cu" "B.Mask" "B.Paste")
			(roundrect_rratio 0.25)
			(net 417 "GND")
			(pinfunction "GND")
			(pintype "power_in")
		)
		(pad "3" smd roundrect
			(at -0.45 -0.25 180)
			(size 0.6 0.25)
			(layers "B.Cu" "B.Mask" "B.Paste")
			(roundrect_rratio 0.25)
			(net 649 "VDD")
			(pinfunction "VCC_{A}")
			(pintype "power_in")
		)
		(pad "4" smd roundrect
			(at -0.45 -0.75 180)
			(size 0.6 0.3)
			(layers "B.Cu" "B.Mask" "B.Paste")
			(roundrect_rratio 0.25)
			(net 352 "/FPGA GPIO/WiFi_CLK")
			(pinfunction "A_{2}")
			(pintype "bidirectional")
		)
		(pad "5" smd roundrect
			(at 0.45 -0.75 180)
			(size 0.6 0.3)
			(layers "B.Cu" "B.Mask" "B.Paste")
			(roundrect_rratio 0.25)
			(net 354 "/FPGA GPIO/WiFi_DATA_2")
			(pinfunction "A_{1}")
			(pintype "bidirectional")
		)
		(pad "6" smd roundrect
			(at 0.45 -0.25 180)
			(size 0.6 0.25)
			(layers "B.Cu" "B.Mask" "B.Paste")
			(roundrect_rratio 0.25)
			(net 649 "VDD")
			(pinfunction "OE")
			(pintype "input")
		)
		(pad "7" smd roundrect
			(at 0.45 0.25 180)
			(size 0.6 0.25)
			(layers "B.Cu" "B.Mask" "B.Paste")
			(roundrect_rratio 0.25)
			(net 50 "+3V3")
			(pinfunction "VCC_{B}")
			(pintype "power_in")
		)
		(pad "8" smd roundrect
			(at 0.45 0.75 180)
			(size 0.6 0.3)
			(layers "B.Cu" "B.Mask" "B.Paste")
			(roundrect_rratio 0.25)
			(net 225 "/FPGA GPIO/WiFi.DAT2")
			(pinfunction "B_{1}")
			(pintype "bidirectional")
		)
	)
	(footprint "antmicro-footprints:C_0402_1005Metric"
		(layer "B.Cu")
		(at 219.911 121.754)
		(descr "Capacitor SMD 0402")
		(tags "capacitor SMD 0402")
		(property "Reference" "C213"
			(at 6.539 3.996 0)
			(layer "B.SilkS")
			(effects
				(font
					(size 0.7 0.7)
					(thickness 0.15)
				)
				(justify right bottom mirror)
			)
		)
		(property "Value" "C_100n_0402"
			(at -1.022927 -2.155213 0)
			(layer "B.Fab")
			(hide yes)
			(effects
				(font
					(size 0.7 0.7)
					(thickness 0.15)
				)
				(justify right bottom mirror)
			)
		)
		(property "Datasheet" "https://www.murata.com/products/productdetail?partno=GRM155R61H104KE14%23"
			(at 0 0 0)
			(layer "F.Fab")
			(hide yes)
			(effects
				(font
					(size 1.27 1.27)
					(thickness 0.15)
				)
			)
		)
		(property "Description" "SMD Multilayer Ceramic Capacitor, 0.1 µF, 50 V, 0402 [1005 Metric], ± 10%, X5R, GRM Series"
			(at 0 0 0)
			(layer "F.Fab")
			(hide yes)
			(effects
				(font
					(size 1.27 1.27)
					(thickness 0.15)
				)
			)
		)
		(property "Author" "Antmicro"
			(at 0 0 0)
			(layer "B.Fab")
			(hide yes)
			(effects
				(font
					(size 1 1)
					(thickness 0.15)
				)
				(justify mirror)
			)
		)
		(property "Dielectric" "X5R"
			(at 0 0 0)
			(layer "B.Fab")
			(hide yes)
			(effects
				(font
					(size 1 1)
					(thickness 0.15)
				)
				(justify mirror)
			)
		)
		(property "License" "Apache-2.0"
			(at 0 0 0)
			(layer "B.Fab")
			(hide yes)
			(effects
				(font
					(size 1 1)
					(thickness 0.15)
				)
				(justify mirror)
			)
		)
		(property "MPN" "GRM155R61H104KE14D"
			(at 0 0 0)
			(layer "B.Fab")
			(hide yes)
			(effects
				(font
					(size 1 1)
					(thickness 0.15)
				)
				(justify mirror)
			)
		)
		(property "Manufacturer" "Murata"
			(at 0 0 0)
			(layer "B.Fab")
			(hide yes)
			(effects
				(font
					(size 1 1)
					(thickness 0.15)
				)
				(justify mirror)
			)
		)
		(property "Public" ""
			(at 0 0 0)
			(layer "B.Fab")
			(hide yes)
			(effects
				(font
					(size 1 1)
					(thickness 0.15)
				)
				(justify mirror)
			)
		)
		(property "Val" "100n"
			(at 0 0 0)
			(layer "B.Fab")
			(hide yes)
			(effects
				(font
					(size 1 1)
					(thickness 0.15)
				)
				(justify mirror)
			)
		)
		(property "Voltage" "50V"
			(at 0 0 0)
			(layer "B.Fab")
			(hide yes)
			(effects
				(font
					(size 1 1)
					(thickness 0.15)
				)
				(justify mirror)
			)
		)
		(sheetname "/Ethernet/")
		(sheetfile "ethernet.kicad_sch")
		(attr smd)
		(fp_rect
			(start -0.925 0.47)
			(end 0.925 -0.47)
			(stroke
				(width 0.05)
				(type default)
			)
			(fill no)
			(layer "B.CrtYd")
		)
		(fp_line
			(start -0.494 -0.248)
			(end -0.494 0.25)
			(stroke
				(width 0.15)
				(type solid)
			)
			(layer "B.Fab")
		)
		(fp_line
			(start -0.494 0.25)
			(end 0.504 0.25)
			(stroke
				(width 0.15)
				(type solid)
			)
			(layer "B.Fab")
		)
		(fp_line
			(start 0.504 -0.248)
			(end -0.494 -0.248)
			(stroke
				(width 0.15)
				(type solid)
			)
			(layer "B.Fab")
		)
		(fp_line
			(start 0.504 0.25)
			(end 0.504 -0.248)
			(stroke
				(width 0.15)
				(type solid)
			)
			(layer "B.Fab")
		)
		(fp_text user "${REFERENCE}"
			(at -0.939 -4.599 180)
			(layer "B.Fab")
			(effects
				(font
					(size 0.7 0.7)
					(thickness 0.15)
				)
				(justify left bottom mirror)
			)
		)
		(fp_text user "Author: Antmicro"
			(at -0.939 -3.399 180)
			(layer "B.Fab")
			(effects
				(font
					(size 0.7 0.7)
					(thickness 0.15)
				)
				(justify left bottom mirror)
			)
		)
		(fp_text user "License: Apache-2.0"
			(at -0.939 -5.799 180)
			(layer "B.Fab")
			(effects
				(font
					(size 0.7 0.7)
					(thickness 0.15)
				)
				(justify left bottom mirror)
			)
		)
		(pad "1" smd roundrect
			(at -0.48 0)
			(size 0.59 0.64)
			(layers "B.Cu" "B.Mask" "B.Paste")
			(roundrect_rratio 0.25)
			(net 417 "GND")
			(pintype "passive")
		)
		(pad "2" smd roundrect
			(at 0.48 0)
			(size 0.59 0.64)
			(layers "B.Cu" "B.Mask" "B.Paste")
			(roundrect_rratio 0.25)
			(net 418 "+2V5")
			(pintype "passive")
		)
	)
)
